(kicad_pcb
	(version 20260206)
	(generator "pcbnew")
	(generator_version "10.0")
	(general
		(thickness 1.6)
		(legacy_teardrops no)
	)
	(paper "A4")
	(title_block
		(title "Bryce Canyon_F.DPB_16315-1-OCP.brd")
		(comment 1 "Bryce Canyon / footprints 1391-1393 of 2223")
	)
	(layers
		(0 "F.Cu" signal "TOP")
		(4 "In1.Cu" signal "L2GND")
		(6 "In2.Cu" signal "L3")
		(8 "In3.Cu" signal "L4GND")
		(10 "In4.Cu" signal "L5")
		(12 "In5.Cu" signal "L6VCC")
		(14 "In6.Cu" signal "L7VCC")
		(16 "In7.Cu" signal "L8")
		(18 "In8.Cu" signal "L9GND")
		(20 "In9.Cu" signal "L10")
		(22 "In10.Cu" signal "L11GND")
		(2 "B.Cu" signal "BOTTOM")
		(9 "F.Adhes" user "F.Adhesive")
		(11 "B.Adhes" user "B.Adhesive")
		(13 "F.Paste" user "Package Geometry/Pastemask Top")
		(15 "B.Paste" user "Package Geometry/Pastemask Bottom")
		(5 "F.SilkS" user "Ref Des/Silkscreen Top")
		(7 "B.SilkS" user "Ref Des/Silkscreen Bottom")
		(1 "F.Mask" user "Board Geometry/Soldermask Top")
		(3 "B.Mask" user "Board Geometry/Soldermask Bottom")
		(17 "Dwgs.User" user "User.Drawings")
		(19 "Cmts.User" user "User.Comments")
		(21 "Eco1.User" user "User.Eco1")
		(23 "Eco2.User" user "User.Eco2")
		(25 "Edge.Cuts" user "Board Geometry/Outline")
		(27 "Margin" user)
		(31 "F.CrtYd" user "Package Geometry/Place Bound Top")
		(29 "B.CrtYd" user "Package Geometry/Place Bound Bottom")
		(35 "F.Fab" user "Ref Des/Assembly Top")
		(33 "B.Fab" user "Ref Des/Assembly Bottom")
	)
	(footprint ""
		(layer "F.Cu")
		(at 64.0588 -162.749992 -90)
		(property "Reference" "VIA48"
			(at 0 0 270)
			(layer "F.SilkS")
			(hide yes)
			(effects
				(font
					(size 1.27 1.27)
				)
			)
		)
		(property "Value" "100OHM-8L-1D6MM-L18L16-GP"
			(at -3.7211 -4.5085 270)
			(unlocked yes)
			(layer "F.Fab")
			(hide yes)
			(effects
				(font
					(size 1.016 1.016)
					(thickness 0.1524)
				)
			)
		)
		(property "Device Type" "VIA-PCIE-4P-394076"
			(at -3.7211 -6.0325 270)
			(unlocked yes)
			(layer "F.Fab")
			(hide yes)
			(effects
				(font
					(size 1.016 1.016)
					(thickness 0.1524)
				)
			)
		)
		(duplicate_pad_numbers_are_jumpers no)
		(fp_rect
			(start -1.9685 0.381)
			(end 1.9685 -0.381)
			(stroke
				(width 0)
				(type default)
			)
			(fill no)
			(layer "F.CrtYd")
		)
		(fp_rect
			(start -1.9685 0.381)
			(end 1.9685 -0.381)
			(stroke
				(width 0)
				(type default)
			)
			(fill no)
			(layer "F.Fab")
		)
		(pad "1" thru_hole circle
			(at -1.5875 0 270)
			(size 0.508 0.508)
			(drill 0.254)
			(layers "*.Cu" "*.Mask")
			(remove_unused_layers no)
			(net "GND")
			(clearance 0.127)
			(thermal_gap 0.127)
		)
		(pad "2" thru_hole circle
			(at -0.5715 0 270)
			(size 0.508 0.508)
			(drill 0.254)
			(layers "*.Cu" "*.Mask")
			(remove_unused_layers no)
			(net "PHY_DRV_A_TO_SCC_A_13_DP")
			(clearance 0.127)
			(thermal_gap 0.127)
		)
		(pad "3" thru_hole circle
			(at 0.5715 0 270)
			(size 0.508 0.508)
			(drill 0.254)
			(layers "*.Cu" "*.Mask")
			(remove_unused_layers no)
			(net "PHY_DRV_A_TO_SCC_A_13_DN")
			(clearance 0.127)
			(thermal_gap 0.127)
		)
		(pad "4" thru_hole circle
			(at 1.5875 0 270)
			(size 0.508 0.508)
			(drill 0.254)
			(layers "*.Cu" "*.Mask")
			(remove_unused_layers no)
			(net "GND")
			(clearance 0.127)
			(thermal_gap 0.127)
		)
	)
	(footprint ""
		(layer "F.Cu")
		(at 461.0989 -167.872918 -90)
		(property "Reference" "Q132"
			(at 0 0 270)
			(layer "F.SilkS")
			(hide yes)
			(effects
				(font
					(size 1.27 1.27)
				)
			)
		)
		(property "Value" "AO4406AL-GP"
			(at -3.707384 -1.5367 270)
			(unlocked yes)
			(layer "F.Fab")
			(hide yes)
			(effects
				(font
					(size 1.016 1.016)
					(thickness 0.1524)
				)
			)
		)
		(property "Device Type" "SOIC8H69"
			(at -3.707384 -3.0607 270)
			(unlocked yes)
			(layer "F.Fab")
			(hide yes)
			(effects
				(font
					(size 1.016 1.016)
					(thickness 0.1524)
				)
			)
		)
		(duplicate_pad_numbers_are_jumpers no)
		(fp_line
			(start -2.6289 3.4417)
			(end -2.6289 1.4732)
			(stroke
				(width 0.381)
				(type default)
			)
			(layer "F.SilkS")
		)
		(fp_line
			(start -2.7432 1.4224)
			(end -2.6416 1.4224)
			(stroke
				(width 0.1524)
				(type default)
			)
			(layer "F.SilkS")
		)
		(fp_line
			(start -2.7432 1.4224)
			(end 2.1336 1.4224)
			(stroke
				(width 0.1524)
				(type default)
			)
			(layer "F.SilkS")
		)
		(fp_line
			(start 2.1336 1.4224)
			(end 2.1336 -1.4224)
			(stroke
				(width 0.1524)
				(type default)
			)
			(layer "F.SilkS")
		)
		(fp_line
			(start -2.1844 -0.0508)
			(end -2.7178 0.508)
			(stroke
				(width 0.1524)
				(type default)
			)
			(layer "F.SilkS")
		)
		(fp_line
			(start -2.7178 -0.508)
			(end -2.1844 -0.0508)
			(stroke
				(width 0.1524)
				(type default)
			)
			(layer "F.SilkS")
		)
		(fp_line
			(start -2.7432 -1.4224)
			(end -2.7432 1.4224)
			(stroke
				(width 0.1524)
				(type default)
			)
			(layer "F.SilkS")
		)
		(fp_line
			(start 2.1336 -1.4224)
			(end -2.7432 -1.4224)
			(stroke
				(width 0.1524)
				(type default)
			)
			(layer "F.SilkS")
		)
		(fp_poly
			(pts
				(xy -2.2098 -1.4224) (xy -2.2098 1.4224) (xy 2.2098 1.4224) (xy 2.2098 -1.4224)
			)
			(stroke
				(width 0)
				(type default)
			)
			(fill yes)
			(layer "F.SilkS")
		)
		(fp_rect
			(start -2.450084 2.999994)
			(end 2.450084 -2.999994)
			(stroke
				(width 0)
				(type default)
			)
			(fill no)
			(layer "F.CrtYd")
		)
		(fp_poly
			(pts
				(xy -2.8194 3.6322) (xy -2.8194 -3.6322) (xy 2.8194 -3.6322) (xy 2.8194 1.18364) (xy 2.450084 1.18364)
				(xy 2.450084 -2.999994) (xy -2.450084 -2.999994) (xy -2.450084 2.999994) (xy 2.450084 2.999994)
				(xy 2.450084 1.18618) (xy 2.8194 1.18618) (xy 2.8194 3.6322)
			)
			(stroke
				(width 0)
				(type default)
			)
			(fill no)
			(layer "F.CrtYd")
		)
		(fp_rect
			(start -2.8194 3.6322)
			(end 2.8194 -3.6322)
			(stroke
				(width 0)
				(type default)
			)
			(fill no)
			(layer "F.Fab")
		)
		(pad "1" smd rect
			(at -1.905 2.54 270)
			(size 0.635 1.651)
			(layers "F.Cu" "F.Mask" "F.Paste")
			(net "P5V_HDD22")
		)
		(pad "2" smd rect
			(at -0.635 2.54 270)
			(size 0.635 1.651)
			(layers "F.Cu" "F.Mask" "F.Paste")
			(net "P5V_HDD22")
		)
		(pad "3" smd rect
			(at 0.635 2.54 270)
			(size 0.635 1.651)
			(layers "F.Cu" "F.Mask" "F.Paste")
			(net "P5V_HDD22")
		)
		(pad "4" smd rect
			(at 1.905 2.54 270)
			(size 0.635 1.651)
			(layers "F.Cu" "F.Mask" "F.Paste")
			(net "SW_HDD_P22")
		)
		(pad "5" smd rect
			(at 1.905 -2.54 270)
			(size 0.635 1.651)
			(layers "F.Cu" "F.Mask" "F.Paste")
			(net "P5V_A_4")
		)
		(pad "6" smd rect
			(at 0.635 -2.54 270)
			(size 0.635 1.651)
			(layers "F.Cu" "F.Mask" "F.Paste")
			(net "P5V_A_4")
		)
		(pad "7" smd rect
			(at -0.635 -2.54 270)
			(size 0.635 1.651)
			(layers "F.Cu" "F.Mask" "F.Paste")
			(net "P5V_A_4")
		)
		(pad "8" smd rect
			(at -1.905 -2.54 270)
			(size 0.635 1.651)
			(layers "F.Cu" "F.Mask" "F.Paste")
			(net "P5V_A_4")
		)
	)
	(footprint ""
		(layer "F.Cu")
		(at 154.399996 -172.909992 -90)
		(property "Reference" "HDDSAS16"
			(at 0 0 270)
			(layer "F.SilkS")
			(hide yes)
			(effects
				(font
					(size 1.27 1.27)
				)
			)
		)
		(property "Value" "SKT-SAS15P-14P-45-GP"
			(at -20.7645 -8.9789 270)
			(unlocked yes)
			(layer "F.Fab")
			(hide yes)
			(effects
				(font
					(size 1.016 1.016)
					(thickness 0.1524)
				)
			)
		)
		(property "Device Type" "10120818-001C-TRLF"
			(at -20.7645 -10.5029 270)
			(unlocked yes)
			(layer "F.Fab")
			(hide yes)
			(effects
				(font
					(size 1.016 1.016)
					(thickness 0.1524)
				)
			)
		)
		(duplicate_pad_numbers_are_jumpers no)
		(fp_line
			(start 1.651 4.2926)
			(end 1.651 3.0099)
			(stroke
				(width 0.1524)
				(type default)
			)
			(layer "F.SilkS")
		)
		(fp_line
			(start 8.509 4.2926)
			(end 1.651 4.2926)
			(stroke
				(width 0.1524)
				(type default)
			)
			(layer "F.SilkS")
		)
		(fp_line
			(start -23.4188 3.0099)
			(end -23.4188 -3.2512)
			(stroke
				(width 0.1524)
				(type default)
			)
			(layer "F.SilkS")
		)
		(fp_line
			(start 1.651 3.0099)
			(end -23.4188 3.0099)
			(stroke
				(width 0.1524)
				(type default)
			)
			(layer "F.SilkS")
		)
		(fp_line
			(start 8.509 3.0099)
			(end 8.509 4.2926)
			(stroke
				(width 0.1524)
				(type default)
			)
			(layer "F.SilkS")
		)
		(fp_line
			(start 23.4188 3.0099)
			(end 8.509 3.0099)
			(stroke
				(width 0.1524)
				(type default)
			)
			(layer "F.SilkS")
		)
		(fp_line
			(start -23.4188 -3.2512)
			(end 23.4188 -3.2512)
			(stroke
				(width 0.1524)
				(type default)
			)
			(layer "F.SilkS")
		)
		(fp_line
			(start 23.4188 -3.2512)
			(end 23.4188 3.0099)
			(stroke
				(width 0.1524)
				(type default)
			)
			(layer "F.SilkS")
		)
		(fp_line
			(start 15.5067 -3.3401)
			(end 16.2687 -3.3401)
			(stroke
				(width 0.3302)
				(type default)
			)
			(layer "F.SilkS")
		)
		(fp_poly
			(pts
				(xy 15.868904 -3.230372) (xy 16.503904 -3.865372) (xy 15.233904 -3.865372)
			)
			(stroke
				(width 0)
				(type default)
			)
			(fill yes)
			(layer "F.SilkS")
		)
		(fp_poly
			(pts
				(xy -22.8727 -2.7559) (xy 22.8727 -2.7559) (xy 22.8727 2.7559) (xy 8.255 2.7559) (xy 8.255 3.5179)
				(xy 1.905 3.5179) (xy 1.905 2.7559) (xy -22.8727 2.7559)
			)
			(stroke
				(width 0)
				(type default)
			)
			(fill no)
			(layer "F.CrtYd")
		)
		(fp_poly
			(pts
				(xy 1.397 4.5466) (xy 1.397 3.2639) (xy -23.6728 3.2639) (xy -23.6728 -3.5052) (xy 23.6728 -3.5052)
				(xy 23.6728 -0.00635) (xy 22.8727 -0.00635) (xy 22.8727 -2.7559) (xy -22.8727 -2.7559) (xy -22.8727 2.7559)
				(xy 1.905 2.7559) (xy 1.905 3.5179) (xy 8.255 3.5179) (xy 8.255 2.7559) (xy 22.8727 2.7559) (xy 22.8727 0.00635)
				(xy 23.6728 0.00635) (xy 23.6728 3.2639) (xy 8.763 3.2639) (xy 8.763 4.5466)
			)
			(stroke
				(width 0)
				(type default)
			)
			(fill no)
			(layer "F.CrtYd")
		)
		(fp_poly
			(pts
				(xy 1.397 4.5466) (xy 1.397 3.2639) (xy -23.6728 3.2639) (xy -23.6728 -3.5052) (xy 23.6728 -3.5052)
				(xy 23.6728 3.2639) (xy 8.763 3.2639) (xy 8.763 4.5466)
			)
			(stroke
				(width 0)
				(type default)
			)
			(fill no)
			(layer "F.Fab")
		)
		(pad "" np_thru_hole circle
			(at -18.874994 0 270)
			(size 0.254 0.254)
			(drill 1.3462)
			(layers "*.Cu" "*.Mask")
			(clearance 0.9017)
			(thermal_gap 0.9017)
		)
		(pad "" np_thru_hole circle
			(at 18.874994 0 270)
			(size 0.254 0.254)
			(drill 0.9398)
			(layers "*.Cu" "*.Mask")
			(clearance 0.6985)
			(thermal_gap 0.6985)
		)
		(pad "G1" smd rect
			(at 21.874988 0 270)
			(size 2.5908 2.5908)
			(layers "F.Cu" "F.Mask" "F.Paste")
			(net "GND")
		)
		(pad "G2" smd rect
			(at -21.874988 0 270)
			(size 2.5908 2.5908)
			(layers "F.Cu" "F.Mask" "F.Paste")
			(net "GND")
		)
		(pad "P1" smd rect
			(at 1.905 -1.82499 270)
			(size 0.6096 2.3622)
			(layers "F.Cu" "F.Mask" "F.Paste")
			(net "Net_2136")
		)
		(pad "P2" smd rect
			(at 0.635 -1.82499 270)
			(size 0.6096 2.3622)
			(layers "F.Cu" "F.Mask" "F.Paste")
			(net "Net_2137")
		)
		(pad "P3" smd rect
			(at -0.635 -1.82499 270)
			(size 0.6096 2.3622)
			(layers "F.Cu" "F.Mask" "F.Paste")
			(net "Net_2138")
		)
		(pad "P4" smd rect
			(at -1.905 -1.82499 270)
			(size 0.6096 2.3622)
			(layers "F.Cu" "F.Mask" "F.Paste")
			(net "GND")
		)
		(pad "P5" smd rect
			(at -3.175 -1.82499 270)
			(size 0.6096 2.3622)
			(layers "F.Cu" "F.Mask" "F.Paste")
			(net "HDD_PRSNT_16")
		)
		(pad "P6" smd rect
			(at -4.445 -1.82499 270)
			(size 0.6096 2.3622)
			(layers "F.Cu" "F.Mask" "F.Paste")
			(net "GND")
		)
		(pad "P7" smd rect
			(at -5.715 -1.82499 270)
			(size 0.6096 2.3622)
			(layers "F.Cu" "F.Mask" "F.Paste")
			(net "5V_PRE_16")
		)
		(pad "P8" smd rect
			(at -6.985 -1.82499 270)
			(size 0.6096 2.3622)
			(layers "F.Cu" "F.Mask" "F.Paste")
			(net "P5V_HDD16")
		)
		(pad "P9" smd rect
			(at -8.255 -1.82499 270)
			(size 0.6096 2.3622)
			(layers "F.Cu" "F.Mask" "F.Paste")
			(net "P5V_HDD16")
		)
		(pad "P10" smd rect
			(at -9.525 -1.82499 270)
			(size 0.6096 2.3622)
			(layers "F.Cu" "F.Mask" "F.Paste")
			(net "GND")
		)
		(pad "P11" smd rect
			(at -10.795 -1.82499 270)
			(size 0.6096 2.3622)
			(layers "F.Cu" "F.Mask" "F.Paste")
			(net "ACT_HDD_16")
		)
		(pad "P12" smd rect
			(at -12.065 -1.82499 270)
			(size 0.6096 2.3622)
			(layers "F.Cu" "F.Mask" "F.Paste")
			(net "GND")
		)
		(pad "P13" smd rect
			(at -13.335 -1.82499 270)
			(size 0.6096 2.3622)
			(layers "F.Cu" "F.Mask" "F.Paste")
			(net "12V_PRE_16")
		)
		(pad "P14" smd rect
			(at -14.605 -1.82499 270)
			(size 0.6096 2.3622)
			(layers "F.Cu" "F.Mask" "F.Paste")
			(net "P12V_HDD16")
		)
		(pad "P15" smd rect
			(at -15.875 -1.82499 270)
			(size 0.6096 2.3622)
			(layers "F.Cu" "F.Mask" "F.Paste")
			(net "P12V_HDD16")
		)
		(pad "S1" smd rect
			(at 15.875 -1.82499 270)
			(size 0.6096 2.3622)
			(layers "F.Cu" "F.Mask" "F.Paste")
			(net "GND")
		)
		(pad "S2" smd rect
			(at 14.605 -1.82499 270)
			(size 0.6096 2.3622)
			(layers "F.Cu" "F.Mask" "F.Paste")
			(net "SAS_HDD_RX_P16")
		)
		(pad "S3" smd rect
			(at 13.335 -1.82499 270)
			(size 0.6096 2.3622)
			(layers "F.Cu" "F.Mask" "F.Paste")
			(net "SAS_HDD_RX_N16")
		)
		(pad "S4" smd rect
			(at 12.065 -1.82499 270)
			(size 0.6096 2.3622)
			(layers "F.Cu" "F.Mask" "F.Paste")
			(net "GND")
		)
		(pad "S5" smd rect
			(at 10.795 -1.82499 270)
			(size 0.6096 2.3622)
			(layers "F.Cu" "F.Mask" "F.Paste")
			(net "PHY_DRV_A_TO_SCC_A_16_DN")
		)
		(pad "S6" smd rect
			(at 9.525 -1.82499 270)
			(size 0.6096 2.3622)
			(layers "F.Cu" "F.Mask" "F.Paste")
			(net "PHY_DRV_A_TO_SCC_A_16_DP")
		)
		(pad "S7" smd rect
			(at 8.255 -1.82499 270)
			(size 0.6096 2.3622)
			(layers "F.Cu" "F.Mask" "F.Paste")
			(net "GND")
		)
		(pad "S8" smd rect
			(at 7.480046 2.845054 270)
			(size 0.508 2.3622)
			(layers "F.Cu" "F.Mask" "F.Paste")
			(net "GND")
		)
		(pad "S9" smd rect
			(at 6.679946 2.845054 270)
			(size 0.508 2.3622)
			(layers "F.Cu" "F.Mask" "F.Paste")
			(net "Net_453")
		)
		(pad "S10" smd rect
			(at 5.8801 2.845054 270)
			(size 0.508 2.3622)
			(layers "F.Cu" "F.Mask" "F.Paste")
			(net "Net_345")
		)
		(pad "S11" smd rect
			(at 5.08 2.845054 270)
			(size 0.508 2.3622)
			(layers "F.Cu" "F.Mask" "F.Paste")
			(net "GND")
		)
		(pad "S12" smd rect
			(at 4.2799 2.845054 270)
			(size 0.508 2.3622)
			(layers "F.Cu" "F.Mask" "F.Paste")
			(net "Net_381")
		)
		(pad "S13" smd rect
			(at 3.480054 2.845054 270)
			(size 0.508 2.3622)
			(layers "F.Cu" "F.Mask" "F.Paste")
			(net "Net_417")
		)
		(pad "S14" smd rect
			(at 2.679954 2.845054 270)
			(size 0.508 2.3622)
			(layers "F.Cu" "F.Mask" "F.Paste")
			(net "GND")
		)
		(zone
			(layer "F.Cu")
			(hatch none 0.5)
			(connect_pads
				(clearance 0)
			)
			(min_thickness 0.25)
			(keepout
				(tracks allowed)
				(vias not_allowed)
				(pads allowed)
				(copperpour not_allowed)
				(footprints allowed)
			)
			(placement
				(enabled no)
				(sheetname "")
			)
			(fill
				(thermal_gap 0.5)
				(thermal_bridge_width 0.5)
				(island_removal_mode 0)
			)
			(polygon
				(pts
					(xy 158.057596 -189.648592) (xy 150.983696 -189.648592) (xy 150.983696 -196.582792) (xy 152.088596 -196.582792)
					(xy 152.088596 -192.467992) (xy 156.711396 -192.467992) (xy 156.711396 -196.582792) (xy 158.057596 -196.582792)
				)
			)
		)
		(zone
			(layer "F.Cu")
			(hatch none 0.5)
			(connect_pads
				(clearance 0)
			)
			(min_thickness 0.25)
			(keepout
				(tracks not_allowed)
				(vias allowed)
				(pads allowed)
				(copperpour not_allowed)
				(footprints allowed)
			)
			(placement
				(enabled no)
				(sheetname "")
			)
			(fill
				(thermal_gap 0.5)
				(thermal_bridge_width 0.5)
				(island_removal_mode 0)
			)
			(polygon
				(pts
					(xy 158.057596 -189.648592) (xy 150.983696 -189.648592) (xy 150.983696 -196.582792) (xy 152.088596 -196.582792)
					(xy 152.088596 -192.467992) (xy 156.711396 -192.467992) (xy 156.711396 -196.582792) (xy 158.057596 -196.582792)
				)
			)
		)
		(zone
			(layer "F.Cu")
			(hatch none 0.5)
			(connect_pads
				(clearance 0)
			)
			(min_thickness 0.25)
			(keepout
				(tracks allowed)
				(vias not_allowed)
				(pads allowed)
				(copperpour not_allowed)
				(footprints allowed)
			)
			(placement
				(enabled no)
				(sheetname "")
			)
			(fill
				(thermal_gap 0.5)
				(thermal_bridge_width 0.5)
				(island_removal_mode 0)
			)
			(polygon
				(pts
					(xy 158.057596 -156.171392) (xy 150.983696 -156.171392) (xy 150.983696 -149.237192) (xy 152.088596 -149.237192)
					(xy 152.088596 -153.351992) (xy 156.711396 -153.351992) (xy 156.711396 -149.237192) (xy 158.057596 -149.237192)
				)
			)
		)
		(zone
			(layer "F.Cu")
			(hatch none 0.5)
			(connect_pads
				(clearance 0)
			)
			(min_thickness 0.25)
			(keepout
				(tracks not_allowed)
				(vias allowed)
				(pads allowed)
				(copperpour not_allowed)
				(footprints allowed)
			)
			(placement
				(enabled no)
				(sheetname "")
			)
			(fill
				(thermal_gap 0.5)
				(thermal_bridge_width 0.5)
				(island_removal_mode 0)
			)
			(polygon
				(pts
					(xy 158.057596 -156.171392) (xy 150.983696 -156.171392) (xy 150.983696 -149.237192) (xy 152.088596 -149.237192)
					(xy 152.088596 -153.351992) (xy 156.711396 -153.351992) (xy 156.711396 -149.237192) (xy 158.057596 -149.237192)
				)
			)
		)
		(zone
			(layers "F.Cu" "B.Cu" "In1.Cu" "In2.Cu" "In3.Cu" "In4.Cu" "In5.Cu" "In6.Cu"
				"In7.Cu" "In8.Cu" "In9.Cu" "In10.Cu"
			)
			(hatch none 0.5)
			(connect_pads
				(clearance 0)
			)
			(min_thickness 0.25)
			(keepout
				(tracks not_allowed)
				(vias allowed)
				(pads allowed)
				(copperpour not_allowed)
				(footprints allowed)
			)
			(placement
				(enabled no)
				(sheetname "")
			)
			(fill
				(thermal_gap 0.5)
				(thermal_bridge_width 0.5)
				(island_removal_mode 0)
			)
			(polygon
				(pts
					(arc
						(start 155.174696 -154.034998)
						(mid 153.625296 -154.034998)
						(end 155.174696 -154.034998)
					)
				)
			)
		)
		(zone
			(layers "F.Cu" "B.Cu" "In1.Cu" "In2.Cu" "In3.Cu" "In4.Cu" "In5.Cu" "In6.Cu"
				"In7.Cu" "In8.Cu" "In9.Cu" "In10.Cu"
			)
			(hatch none 0.5)
			(connect_pads
				(clearance 0)
			)
			(min_thickness 0.25)
			(keepout
				(tracks not_allowed)
				(vias allowed)
				(pads allowed)
				(copperpour not_allowed)
				(footprints allowed)
			)
			(placement
				(enabled no)
				(sheetname "")
			)
			(fill
				(thermal_gap 0.5)
				(thermal_bridge_width 0.5)
				(island_removal_mode 0)
			)
			(polygon
				(pts
					(arc
						(start 155.377896 -191.784986)
						(mid 153.422096 -191.784986)
						(end 155.377896 -191.784986)
					)
				)
			)
		)
	)
)
